# T6G (Grand Teton) — schematic netlist excerpt (pin names and nets, part order shuffled) for the footprints in the layout excerpt that follows; sources: Cadence DE-HDL packaged netlist, KiCad conversion of 04192023_DAF0TMB3IC0_F0TG_MB_C_brd_V02_OCP.brd

C2257  Q_CAP  0.1UF 25V 10% X7R  pkg 0402  page 233 : A = VFG3P3_CLK_GEN ; B = GND
R428  Q_RES  0 5% CHIP  pkg 0402LF  page 159 : A = I3C_1_SPD_DDRGL_CPU0_SCL ; B = I3C_1_SPD_DDRGL_CPU0_R_SCL

(kicad_pcb
	(version 20260206)
	(generator "pcbnew")
	(generator_version "10.0")
	(general
		(thickness 1.6)
		(legacy_teardrops no)
	)
	(paper "A4")
	(title_block
		(title "04192023_DAF0TMB3IC0_F0TG_MB_C_brd_V02_OCP.brd")
		(comment 1 "Grand Teton / footprints 5225-5226 of 8354")
	)
	(layers
		(0 "F.Cu" signal "TOP")
		(4 "In1.Cu" signal "GND")
		(6 "In2.Cu" signal "IN1")
		(8 "In3.Cu" signal "GND1")
		(10 "In4.Cu" signal "IN2")
		(12 "In5.Cu" signal "GND2")
		(14 "In6.Cu" signal "IN3")
		(16 "In7.Cu" signal "GND3")
		(18 "In8.Cu" signal "VCC")
		(20 "In9.Cu" signal "VCC1")
		(22 "In10.Cu" signal "GND4")
		(24 "In11.Cu" signal "IN4")
		(26 "In12.Cu" signal "GND5")
		(28 "In13.Cu" signal "IN5")
		(30 "In14.Cu" signal "GND6")
		(32 "In15.Cu" signal "IN6")
		(34 "In16.Cu" signal "GND7")
		(2 "B.Cu" signal "BOTTOM")
		(9 "F.Adhes" user "F.Adhesive")
		(11 "B.Adhes" user "B.Adhesive")
		(13 "F.Paste" user "Package Geometry/Pastemask Top")
		(15 "B.Paste" user "Package Geometry/Pastemask Bottom")
		(5 "F.SilkS" user "Ref Des/Silkscreen Top")
		(7 "B.SilkS" user "Ref Des/Silkscreen Bottom")
		(1 "F.Mask" user "Board Geometry/Soldermask Top")
		(3 "B.Mask" user "Board Geometry/Soldermask Bottom")
		(17 "Dwgs.User" user "User.Drawings")
		(19 "Cmts.User" user "User.Comments")
		(21 "Eco1.User" user "User.Eco1")
		(23 "Eco2.User" user "User.Eco2")
		(25 "Edge.Cuts" user "Board Geometry/Outline")
		(27 "Margin" user)
		(31 "F.CrtYd" user "Package Geometry/Place Bound Top")
		(29 "B.CrtYd" user "Package Geometry/Place Bound Bottom")
		(35 "F.Fab" user "Ref Des/Assembly Top")
		(33 "B.Fab" user "Ref Des/Assembly Bottom")
	)
	(footprint ""
		(layer "B.Cu")
		(at 380.282958 -205.101952 -90)
		(property "Reference" "R428"
			(at 0 0 90)
			(layer "B.SilkS")
			(hide yes)
			(effects
				(font
					(size 1.27 1.27)
				)
				(justify mirror)
			)
		)
		(property "Value" ""
			(at 0 0 90)
			(layer "B.Fab")
			(effects
				(font
					(size 1.27 1.27)
				)
				(justify mirror)
			)
		)
		(duplicate_pad_numbers_are_jumpers no)
		(fp_line
			(start -0.7874 0.4064)
			(end 0.7874 0.4064)
			(stroke
				(width 0.1524)
				(type default)
			)
			(layer "B.SilkS")
		)
		(fp_line
			(start 0.7874 0.4064)
			(end 0.7874 -0.4064)
			(stroke
				(width 0.1524)
				(type default)
			)
			(layer "B.SilkS")
		)
		(fp_line
			(start -0.7874 -0.4064)
			(end -0.7874 0.4064)
			(stroke
				(width 0.1524)
				(type default)
			)
			(layer "B.SilkS")
		)
		(fp_line
			(start 0.7874 -0.4064)
			(end -0.7874 -0.4064)
			(stroke
				(width 0.1524)
				(type default)
			)
			(layer "B.SilkS")
		)
		(fp_line
			(start -0.67945 0.3048)
			(end -0.120396 0.3048)
			(stroke
				(width 0.1)
				(type default)
			)
			(layer "B.Fab")
		)
		(fp_line
			(start -0.120396 0.3048)
			(end -0.120396 0.2794)
			(stroke
				(width 0.1)
				(type default)
			)
			(layer "B.Fab")
		)
		(fp_line
			(start 0.12065 0.3048)
			(end 0.67945 0.3048)
			(stroke
				(width 0.1)
				(type default)
			)
			(layer "B.Fab")
		)
		(fp_line
			(start 0.67945 0.3048)
			(end 0.67945 -0.305054)
			(stroke
				(width 0.1)
				(type default)
			)
			(layer "B.Fab")
		)
		(fp_line
			(start -0.120396 0.2794)
			(end 0.12065 0.2794)
			(stroke
				(width 0.1)
				(type default)
			)
			(layer "B.Fab")
		)
		(fp_line
			(start 0.12065 0.2794)
			(end 0.12065 0.3048)
			(stroke
				(width 0.1)
				(type default)
			)
			(layer "B.Fab")
		)
		(fp_line
			(start -0.12065 -0.2794)
			(end -0.12065 -0.3048)
			(stroke
				(width 0.1)
				(type default)
			)
			(layer "B.Fab")
		)
		(fp_line
			(start 0.12065 -0.2794)
			(end -0.12065 -0.2794)
			(stroke
				(width 0.1)
				(type default)
			)
			(layer "B.Fab")
		)
		(fp_line
			(start -0.67945 -0.3048)
			(end -0.67945 0.3048)
			(stroke
				(width 0.1)
				(type default)
			)
			(layer "B.Fab")
		)
		(fp_line
			(start -0.12065 -0.3048)
			(end -0.67945 -0.3048)
			(stroke
				(width 0.1)
				(type default)
			)
			(layer "B.Fab")
		)
		(fp_line
			(start 0.12065 -0.305054)
			(end 0.12065 -0.2794)
			(stroke
				(width 0.1)
				(type default)
			)
			(layer "B.Fab")
		)
		(fp_line
			(start 0.67945 -0.305054)
			(end 0.12065 -0.305054)
			(stroke
				(width 0.1)
				(type default)
			)
			(layer "B.Fab")
		)
		(pad "1" smd rect
			(at 0.40005 0 270)
			(size 0.4572 0.508)
			(layers "B.Cu" "B.Mask" "B.Paste")
			(net "I3C_1_SPD_DDRGL_CPU0_SCL")
		)
		(pad "2" smd rect
			(at -0.40005 0 270)
			(size 0.4572 0.508)
			(layers "B.Cu" "B.Mask" "B.Paste")
			(net "I3C_1_SPD_DDRGL_CPU0_R_SCL")
		)
	)
	(footprint ""
		(layer "B.Cu")
		(at 12.060428 -135.63219 180)
		(property "Reference" "C2257"
			(at 0 0 0)
			(layer "B.SilkS")
			(hide yes)
			(effects
				(font
					(size 1.27 1.27)
				)
				(justify mirror)
			)
		)
		(property "Value" ""
			(at 0 0 0)
			(layer "B.Fab")
			(effects
				(font
					(size 1.27 1.27)
				)
				(justify mirror)
			)
		)
		(duplicate_pad_numbers_are_jumpers no)
		(fp_line
			(start 0.7874 0.4064)
			(end 0.7874 -0.4064)
			(stroke
				(width 0.1524)
				(type default)
			)
			(layer "B.SilkS")
		)
		(fp_line
			(start 0.7874 -0.4064)
			(end -0.7874 -0.4064)
			(stroke
				(width 0.1524)
				(type default)
			)
			(layer "B.SilkS")
		)
		(fp_line
			(start -0.7874 0.4064)
			(end 0.7874 0.4064)
			(stroke
				(width 0.1524)
				(type default)
			)
			(layer "B.SilkS")
		)
		(fp_line
			(start -0.7874 -0.4064)
			(end -0.7874 0.4064)
			(stroke
				(width 0.1524)
				(type default)
			)
			(layer "B.SilkS")
		)
		(fp_line
			(start 0.67945 0.3048)
			(end 0.67945 -0.305054)
			(stroke
				(width 0.1)
				(type default)
			)
			(layer "B.Fab")
		)
		(fp_line
			(start 0.67945 -0.305054)
			(end 0.12065 -0.305054)
			(stroke
				(width 0.1)
				(type default)
			)
			(layer "B.Fab")
		)
		(fp_line
			(start 0.12065 0.3048)
			(end 0.67945 0.3048)
			(stroke
				(width 0.1)
				(type default)
			)
			(layer "B.Fab")
		)
		(fp_line
			(start 0.12065 0.2794)
			(end 0.12065 0.3048)
			(stroke
				(width 0.1)
				(type default)
			)
			(layer "B.Fab")
		)
		(fp_line
			(start 0.12065 -0.2794)
			(end -0.12065 -0.2794)
			(stroke
				(width 0.1)
				(type default)
			)
			(layer "B.Fab")
		)
		(fp_line
			(start 0.12065 -0.305054)
			(end 0.12065 -0.2794)
			(stroke
				(width 0.1)
				(type default)
			)
			(layer "B.Fab")
		)
		(fp_line
			(start -0.120396 0.3048)
			(end -0.120396 0.2794)
			(stroke
				(width 0.1)
				(type default)
			)
			(layer "B.Fab")
		)
		(fp_line
			(start -0.120396 0.2794)
			(end 0.12065 0.2794)
			(stroke
				(width 0.1)
				(type default)
			)
			(layer "B.Fab")
		)
		(fp_line
			(start -0.12065 -0.2794)
			(end -0.12065 -0.3048)
			(stroke
				(width 0.1)
				(type default)
			)
			(layer "B.Fab")
		)
		(fp_line
			(start -0.12065 -0.3048)
			(end -0.67945 -0.3048)
			(stroke
				(width 0.1)
				(type default)
			)
			(layer "B.Fab")
		)
		(fp_line
			(start -0.67945 0.3048)
			(end -0.120396 0.3048)
			(stroke
				(width 0.1)
				(type default)
			)
			(layer "B.Fab")
		)
		(fp_line
			(start -0.67945 -0.3048)
			(end -0.67945 0.3048)
			(stroke
				(width 0.1)
				(type default)
			)
			(layer "B.Fab")
		)
		(pad "1" smd circle
			(at 0.40005 0)
			(size 0 0)
			(layers "B.Cu" "B.Mask" "B.Paste")
			(net "VFG3P3_CLK_GEN")
		)
		(pad "2" smd circle
			(at -0.40005 0)
			(size 0 0)
			(layers "B.Cu" "B.Mask" "B.Paste")
			(net "GND")
		)
	)
)
